# T6G (Grand Teton) — schematic netlist excerpt (pin names and nets, part order shuffled) for the footprints in the layout excerpt that follows; sources: Cadence DE-HDL packaged netlist, KiCad conversion of 04192023_DAF0TMB3IC0_F0TG_MB_C_brd_V02_OCP.brd

R3578  Q_RES  10 1% CHIP  pkg 0402LF  page 237 : A = P12V_SCM_R ; B = VSENSE_P12V_INA230_5_INP
C6742  Q_CAP_DIFFBUS  DIFF BUS_0.22UF 6.3V 20% X6S  pkg C0201  page 352 : \1\ = P5E_CPU1_P3_TX_BUF_C_DN<8> ; \2\ = P5E_CPU1_P3_TX_BUF_DN<8>
C2402  Q_CAP  22UF 4V 20% X6S  pkg C0402  page 73 : A = PVDDCR_CPU1_P1 ; B = GND

(kicad_pcb
	(version 20260206)
	(generator "pcbnew")
	(generator_version "10.0")
	(general
		(thickness 1.6)
		(legacy_teardrops no)
	)
	(paper "A4")
	(title_block
		(title "04192023_DAF0TMB3IC0_F0TG_MB_C_brd_V02_OCP.brd")
		(comment 1 "Grand Teton / footprints 6897-6899 of 8354")
	)
	(layers
		(0 "F.Cu" signal "TOP")
		(4 "In1.Cu" signal "GND")
		(6 "In2.Cu" signal "IN1")
		(8 "In3.Cu" signal "GND1")
		(10 "In4.Cu" signal "IN2")
		(12 "In5.Cu" signal "GND2")
		(14 "In6.Cu" signal "IN3")
		(16 "In7.Cu" signal "GND3")
		(18 "In8.Cu" signal "VCC")
		(20 "In9.Cu" signal "VCC1")
		(22 "In10.Cu" signal "GND4")
		(24 "In11.Cu" signal "IN4")
		(26 "In12.Cu" signal "GND5")
		(28 "In13.Cu" signal "IN5")
		(30 "In14.Cu" signal "GND6")
		(32 "In15.Cu" signal "IN6")
		(34 "In16.Cu" signal "GND7")
		(2 "B.Cu" signal "BOTTOM")
		(9 "F.Adhes" user "F.Adhesive")
		(11 "B.Adhes" user "B.Adhesive")
		(13 "F.Paste" user "Package Geometry/Pastemask Top")
		(15 "B.Paste" user "Package Geometry/Pastemask Bottom")
		(5 "F.SilkS" user "Ref Des/Silkscreen Top")
		(7 "B.SilkS" user "Ref Des/Silkscreen Bottom")
		(1 "F.Mask" user "Board Geometry/Soldermask Top")
		(3 "B.Mask" user "Board Geometry/Soldermask Bottom")
		(17 "Dwgs.User" user "User.Drawings")
		(19 "Cmts.User" user "User.Comments")
		(21 "Eco1.User" user "User.Eco1")
		(23 "Eco2.User" user "User.Eco2")
		(25 "Edge.Cuts" user "Board Geometry/Outline")
		(27 "Margin" user)
		(31 "F.CrtYd" user "Package Geometry/Place Bound Top")
		(29 "B.CrtYd" user "Package Geometry/Place Bound Bottom")
		(35 "F.Fab" user "Ref Des/Assembly Top")
		(33 "B.Fab" user "Ref Des/Assembly Bottom")
	)
	(footprint ""
		(layer "B.Cu")
		(at 107.355386 -269.307564 180)
		(property "Reference" "C2402"
			(at 0 0 0)
			(layer "B.SilkS")
			(hide yes)
			(effects
				(font
					(size 1.27 1.27)
				)
				(justify mirror)
			)
		)
		(property "Value" ""
			(at 0 0 0)
			(layer "B.Fab")
			(effects
				(font
					(size 1.27 1.27)
				)
				(justify mirror)
			)
		)
		(duplicate_pad_numbers_are_jumpers no)
		(fp_line
			(start 0.7874 0.4064)
			(end 0.7874 -0.4064)
			(stroke
				(width 0.1524)
				(type default)
			)
			(layer "B.SilkS")
		)
		(fp_line
			(start 0.7874 -0.4064)
			(end -0.7874 -0.4064)
			(stroke
				(width 0.1524)
				(type default)
			)
			(layer "B.SilkS")
		)
		(fp_line
			(start -0.7874 0.4064)
			(end 0.7874 0.4064)
			(stroke
				(width 0.1524)
				(type default)
			)
			(layer "B.SilkS")
		)
		(fp_line
			(start -0.7874 -0.4064)
			(end -0.7874 0.4064)
			(stroke
				(width 0.1524)
				(type default)
			)
			(layer "B.SilkS")
		)
		(fp_line
			(start 0.67945 0.3048)
			(end 0.67945 -0.305054)
			(stroke
				(width 0.1)
				(type default)
			)
			(layer "B.Fab")
		)
		(fp_line
			(start 0.67945 -0.305054)
			(end 0.12065 -0.305054)
			(stroke
				(width 0.1)
				(type default)
			)
			(layer "B.Fab")
		)
		(fp_line
			(start 0.12065 0.3048)
			(end 0.67945 0.3048)
			(stroke
				(width 0.1)
				(type default)
			)
			(layer "B.Fab")
		)
		(fp_line
			(start 0.12065 0.2794)
			(end 0.12065 0.3048)
			(stroke
				(width 0.1)
				(type default)
			)
			(layer "B.Fab")
		)
		(fp_line
			(start 0.12065 -0.2794)
			(end -0.12065 -0.2794)
			(stroke
				(width 0.1)
				(type default)
			)
			(layer "B.Fab")
		)
		(fp_line
			(start 0.12065 -0.305054)
			(end 0.12065 -0.2794)
			(stroke
				(width 0.1)
				(type default)
			)
			(layer "B.Fab")
		)
		(fp_line
			(start -0.120396 0.3048)
			(end -0.120396 0.2794)
			(stroke
				(width 0.1)
				(type default)
			)
			(layer "B.Fab")
		)
		(fp_line
			(start -0.120396 0.2794)
			(end 0.12065 0.2794)
			(stroke
				(width 0.1)
				(type default)
			)
			(layer "B.Fab")
		)
		(fp_line
			(start -0.12065 -0.2794)
			(end -0.12065 -0.3048)
			(stroke
				(width 0.1)
				(type default)
			)
			(layer "B.Fab")
		)
		(fp_line
			(start -0.12065 -0.3048)
			(end -0.67945 -0.3048)
			(stroke
				(width 0.1)
				(type default)
			)
			(layer "B.Fab")
		)
		(fp_line
			(start -0.67945 0.3048)
			(end -0.120396 0.3048)
			(stroke
				(width 0.1)
				(type default)
			)
			(layer "B.Fab")
		)
		(fp_line
			(start -0.67945 -0.3048)
			(end -0.67945 0.3048)
			(stroke
				(width 0.1)
				(type default)
			)
			(layer "B.Fab")
		)
		(pad "1" smd circle
			(at 0.40005 0)
			(size 0 0)
			(layers "B.Cu" "B.Mask" "B.Paste")
			(net "PVDDCR_CPU1_P1")
		)
		(pad "2" smd circle
			(at -0.40005 0)
			(size 0 0)
			(layers "B.Cu" "B.Mask" "B.Paste")
			(net "GND")
		)
	)
	(footprint ""
		(layer "B.Cu")
		(at 140.906246 -408.517344 90)
		(property "Reference" "C6742"
			(at 0 0 90)
			(layer "B.SilkS")
			(hide yes)
			(effects
				(font
					(size 1.27 1.27)
				)
				(justify mirror)
			)
		)
		(property "Value" ""
			(at 0 0 90)
			(layer "B.Fab")
			(effects
				(font
					(size 1.27 1.27)
				)
				(justify mirror)
			)
		)
		(duplicate_pad_numbers_are_jumpers no)
		(fp_line
			(start 0.299974 -0.150114)
			(end -0.299974 -0.150114)
			(stroke
				(width 0.1)
				(type default)
			)
			(layer "B.Fab")
		)
		(fp_line
			(start -0.299974 -0.150114)
			(end -0.299974 0.150114)
			(stroke
				(width 0.1)
				(type default)
			)
			(layer "B.Fab")
		)
		(fp_line
			(start 0.299974 0.150114)
			(end 0.299974 -0.150114)
			(stroke
				(width 0.1)
				(type default)
			)
			(layer "B.Fab")
		)
		(fp_line
			(start -0.299974 0.150114)
			(end 0.299974 0.150114)
			(stroke
				(width 0.1)
				(type default)
			)
			(layer "B.Fab")
		)
		(pad "1" smd rect
			(at 0.2667 0 270)
			(size 0.3048 0.381)
			(layers "B.Cu" "B.Mask" "B.Paste")
			(net "P5E_CPU1_P3_TX_BUF_C_DN<8>")
		)
		(pad "2" smd rect
			(at -0.2667 0 270)
			(size 0.3048 0.381)
			(layers "B.Cu" "B.Mask" "B.Paste")
			(net "P5E_CPU1_P3_TX_BUF_DN<8>")
		)
	)
	(footprint ""
		(layer "B.Cu")
		(at 203.33208 -36.642548 180)
		(property "Reference" "R3578"
			(at 0 0 0)
			(layer "B.SilkS")
			(hide yes)
			(effects
				(font
					(size 1.27 1.27)
				)
				(justify mirror)
			)
		)
		(property "Value" ""
			(at 0 0 0)
			(layer "B.Fab")
			(effects
				(font
					(size 1.27 1.27)
				)
				(justify mirror)
			)
		)
		(duplicate_pad_numbers_are_jumpers no)
		(fp_line
			(start 0.7874 0.4064)
			(end 0.7874 -0.4064)
			(stroke
				(width 0.1524)
				(type default)
			)
			(layer "B.SilkS")
		)
		(fp_line
			(start 0.7874 -0.4064)
			(end -0.7874 -0.4064)
			(stroke
				(width 0.1524)
				(type default)
			)
			(layer "B.SilkS")
		)
		(fp_line
			(start -0.7874 0.4064)
			(end 0.7874 0.4064)
			(stroke
				(width 0.1524)
				(type default)
			)
			(layer "B.SilkS")
		)
		(fp_line
			(start -0.7874 -0.4064)
			(end -0.7874 0.4064)
			(stroke
				(width 0.1524)
				(type default)
			)
			(layer "B.SilkS")
		)
		(fp_line
			(start 0.67945 0.3048)
			(end 0.67945 -0.305054)
			(stroke
				(width 0.1)
				(type default)
			)
			(layer "B.Fab")
		)
		(fp_line
			(start 0.67945 -0.305054)
			(end 0.12065 -0.305054)
			(stroke
				(width 0.1)
				(type default)
			)
			(layer "B.Fab")
		)
		(fp_line
			(start 0.12065 0.3048)
			(end 0.67945 0.3048)
			(stroke
				(width 0.1)
				(type default)
			)
			(layer "B.Fab")
		)
		(fp_line
			(start 0.12065 0.2794)
			(end 0.12065 0.3048)
			(stroke
				(width 0.1)
				(type default)
			)
			(layer "B.Fab")
		)
		(fp_line
			(start 0.12065 -0.2794)
			(end -0.12065 -0.2794)
			(stroke
				(width 0.1)
				(type default)
			)
			(layer "B.Fab")
		)
		(fp_line
			(start 0.12065 -0.305054)
			(end 0.12065 -0.2794)
			(stroke
				(width 0.1)
				(type default)
			)
			(layer "B.Fab")
		)
		(fp_line
			(start -0.120396 0.3048)
			(end -0.120396 0.2794)
			(stroke
				(width 0.1)
				(type default)
			)
			(layer "B.Fab")
		)
		(fp_line
			(start -0.120396 0.2794)
			(end 0.12065 0.2794)
			(stroke
				(width 0.1)
				(type default)
			)
			(layer "B.Fab")
		)
		(fp_line
			(start -0.12065 -0.2794)
			(end -0.12065 -0.3048)
			(stroke
				(width 0.1)
				(type default)
			)
			(layer "B.Fab")
		)
		(fp_line
			(start -0.12065 -0.3048)
			(end -0.67945 -0.3048)
			(stroke
				(width 0.1)
				(type default)
			)
			(layer "B.Fab")
		)
		(fp_line
			(start -0.67945 0.3048)
			(end -0.120396 0.3048)
			(stroke
				(width 0.1)
				(type default)
			)
			(layer "B.Fab")
		)
		(fp_line
			(start -0.67945 -0.3048)
			(end -0.67945 0.3048)
			(stroke
				(width 0.1)
				(type default)
			)
			(layer "B.Fab")
		)
		(pad "1" smd circle
			(at 0.40005 0)
			(size 0 0)
			(layers "B.Cu" "B.Mask" "B.Paste")
			(net "P12V_SCM_R")
		)
		(pad "2" smd circle
			(at -0.40005 0)
			(size 0 0)
			(layers "B.Cu" "B.Mask" "B.Paste")
			(net "VSENSE_P12V_INA230_5_INP")
		)
	)
)
